(kicad_pcb
	(version 20260206)
	(generator "pcbnew")
	(generator_version "10.0")
	(general
		(thickness 1.6)
		(legacy_teardrops no)
	)
	(paper "A4")
	(title_block
		(title "Bryce Canyon_SCC_16316-1_OCP.brd")
		(comment 1 "Bryce Canyon / footprints 854-863 of 1561")
	)
	(layers
		(0 "F.Cu" signal "TOP")
		(4 "In1.Cu" signal "L2GND")
		(6 "In2.Cu" signal "L3")
		(8 "In3.Cu" signal "L4VCC")
		(10 "In4.Cu" signal "L5VCC")
		(12 "In5.Cu" signal "L6")
		(14 "In6.Cu" signal "L7GND")
		(2 "B.Cu" signal "BOTTOM")
		(9 "F.Adhes" user "F.Adhesive")
		(11 "B.Adhes" user "B.Adhesive")
		(13 "F.Paste" user "Package Geometry/Pastemask Top")
		(15 "B.Paste" user "Package Geometry/Pastemask Bottom")
		(5 "F.SilkS" user "Ref Des/Silkscreen Top")
		(7 "B.SilkS" user "Ref Des/Silkscreen Bottom")
		(1 "F.Mask" user "Board Geometry/Soldermask Top")
		(3 "B.Mask" user "Board Geometry/Soldermask Bottom")
		(17 "Dwgs.User" user "User.Drawings")
		(19 "Cmts.User" user "User.Comments")
		(21 "Eco1.User" user "User.Eco1")
		(23 "Eco2.User" user "User.Eco2")
		(25 "Edge.Cuts" user "Board Geometry/Outline")
		(27 "Margin" user)
		(31 "F.CrtYd" user "Package Geometry/Place Bound Top")
		(29 "B.CrtYd" user "Package Geometry/Place Bound Bottom")
		(35 "F.Fab" user "Ref Des/Assembly Top")
		(33 "B.Fab" user "Ref Des/Assembly Bottom")
	)
	(footprint ""
		(layer "B.Cu")
		(at 180.514498 -51.451256 -90)
		(property "Reference" "TP112"
			(at 0 0 90)
			(layer "B.SilkS")
			(hide yes)
			(effects
				(font
					(size 1.27 1.27)
				)
				(justify mirror)
			)
		)
		(property "Value" "TPAD28-2-GP"
			(at 0.0127 -1.6637 270)
			(unlocked yes)
			(layer "B.Fab")
			(hide yes)
			(effects
				(font
					(size 1.016 1.016)
					(thickness 0.1524)
				)
				(justify mirror)
			)
		)
		(property "Device Type" "TPAD28"
			(at 0.0127 -3.1877 270)
			(unlocked yes)
			(layer "B.Fab")
			(hide yes)
			(effects
				(font
					(size 1.016 1.016)
					(thickness 0.1524)
				)
				(justify mirror)
			)
		)
		(duplicate_pad_numbers_are_jumpers no)
		(fp_poly
			(pts
				(arc
					(start 0 -0.3556)
					(mid 0 0.3556)
					(end 0 -0.3556)
				)
			)
			(stroke
				(width 0)
				(type default)
			)
			(fill no)
			(layer "B.CrtYd")
		)
		(fp_poly
			(pts
				(arc
					(start 0 -0.6096)
					(mid 0 0.6096)
					(end 0 -0.6096)
				)
			)
			(stroke
				(width 0)
				(type default)
			)
			(fill no)
			(layer "B.Fab")
		)
		(pad "1" smd circle
			(at 0 0 90)
			(size 0.7112 0.7112)
			(layers "B.Cu" "B.Mask" "B.Paste")
			(net "XM_CLE")
		)
	)
	(footprint ""
		(layer "B.Cu")
		(at 184.465468 -40.05961 90)
		(property "Reference" "C489"
			(at 0 0 90)
			(layer "B.SilkS")
			(hide yes)
			(effects
				(font
					(size 1.27 1.27)
				)
				(justify mirror)
			)
		)
		(property "Value" "SCD1U6D3V1KX-GP"
			(at 2.8321 -1.7399 90)
			(unlocked yes)
			(layer "B.Fab")
			(hide yes)
			(effects
				(font
					(size 1.016 1.016)
					(thickness 0.1524)
				)
				(justify mirror)
			)
		)
		(property "Device Type" "C0201H13"
			(at 2.8321 -3.2639 90)
			(unlocked yes)
			(layer "B.Fab")
			(hide yes)
			(effects
				(font
					(size 1.016 1.016)
					(thickness 0.1524)
				)
				(justify mirror)
			)
		)
		(duplicate_pad_numbers_are_jumpers no)
		(fp_rect
			(start 0.2794 0.6477)
			(end -0.2794 -0.6477)
			(stroke
				(width 0)
				(type default)
			)
			(fill no)
			(layer "B.CrtYd")
		)
		(fp_rect
			(start 0.2794 0.6477)
			(end -0.2794 -0.6477)
			(stroke
				(width 0)
				(type default)
			)
			(fill no)
			(layer "B.Fab")
		)
		(pad "1" smd custom
			(at 0 -0.2794 270)
			(size 0.0762 0.0762)
			(layers "B.Cu" "B.Mask" "B.Paste")
			(net "P1V8_C")
			(options
				(clearance outline)
				(anchor circle)
			)
			(primitives
				(gr_poly
					(pts
						(arc
							(start 0.1524 0.127)
							(mid 0.137521 0.162921)
							(end 0.1016 0.1778)
						)
						(arc
							(start -0.1016 0.1778)
							(mid -0.137521 0.162921)
							(end -0.1524 0.127)
						)
						(arc
							(start -0.1524 -0.127)
							(mid -0.137521 -0.162921)
							(end -0.1016 -0.1778)
						)
						(arc
							(start 0.1016 -0.1778)
							(mid 0.137521 -0.162921)
							(end 0.1524 -0.127)
						)
					)
					(width 0)
					(fill yes)
				)
			)
		)
		(pad "2" smd custom
			(at 0 0.2794 270)
			(size 0.0762 0.0762)
			(layers "B.Cu" "B.Mask" "B.Paste")
			(net "GND")
			(options
				(clearance outline)
				(anchor circle)
			)
			(primitives
				(gr_poly
					(pts
						(arc
							(start 0.1524 0.127)
							(mid 0.137521 0.162921)
							(end 0.1016 0.1778)
						)
						(arc
							(start -0.1016 0.1778)
							(mid -0.137521 0.162921)
							(end -0.1524 0.127)
						)
						(arc
							(start -0.1524 -0.127)
							(mid -0.137521 -0.162921)
							(end -0.1016 -0.1778)
						)
						(arc
							(start 0.1016 -0.1778)
							(mid 0.137521 -0.162921)
							(end 0.1524 -0.127)
						)
					)
					(width 0)
					(fill yes)
				)
			)
		)
	)
	(footprint ""
		(layer "B.Cu")
		(at 124.5362 -73.4822 -90)
		(property "Reference" "C244"
			(at 0 0 90)
			(layer "B.SilkS")
			(hide yes)
			(effects
				(font
					(size 1.27 1.27)
				)
				(justify mirror)
			)
		)
		(property "Value" "SCD1U6D3V1KX-GP"
			(at 2.8321 -1.7399 270)
			(unlocked yes)
			(layer "B.Fab")
			(hide yes)
			(effects
				(font
					(size 1.016 1.016)
					(thickness 0.1524)
				)
				(justify mirror)
			)
		)
		(property "Device Type" "C0201H13"
			(at 2.8321 -3.2639 270)
			(unlocked yes)
			(layer "B.Fab")
			(hide yes)
			(effects
				(font
					(size 1.016 1.016)
					(thickness 0.1524)
				)
				(justify mirror)
			)
		)
		(duplicate_pad_numbers_are_jumpers no)
		(fp_rect
			(start 0.2794 0.6477)
			(end -0.2794 -0.6477)
			(stroke
				(width 0)
				(type default)
			)
			(fill no)
			(layer "B.CrtYd")
		)
		(fp_rect
			(start 0.2794 0.6477)
			(end -0.2794 -0.6477)
			(stroke
				(width 0)
				(type default)
			)
			(fill no)
			(layer "B.Fab")
		)
		(pad "1" smd custom
			(at 0 -0.2794 90)
			(size 0.0762 0.0762)
			(layers "B.Cu" "B.Mask" "B.Paste")
			(net "GB_VDDA")
			(options
				(clearance outline)
				(anchor circle)
			)
			(primitives
				(gr_poly
					(pts
						(arc
							(start 0.1524 0.127)
							(mid 0.137521 0.162921)
							(end 0.1016 0.1778)
						)
						(arc
							(start -0.1016 0.1778)
							(mid -0.137521 0.162921)
							(end -0.1524 0.127)
						)
						(arc
							(start -0.1524 -0.127)
							(mid -0.137521 -0.162921)
							(end -0.1016 -0.1778)
						)
						(arc
							(start 0.1016 -0.1778)
							(mid 0.137521 -0.162921)
							(end 0.1524 -0.127)
						)
					)
					(width 0)
					(fill yes)
				)
			)
		)
		(pad "2" smd custom
			(at 0 0.2794 90)
			(size 0.0762 0.0762)
			(layers "B.Cu" "B.Mask" "B.Paste")
			(net "GND")
			(options
				(clearance outline)
				(anchor circle)
			)
			(primitives
				(gr_poly
					(pts
						(arc
							(start 0.1524 0.127)
							(mid 0.137521 0.162921)
							(end 0.1016 0.1778)
						)
						(arc
							(start -0.1016 0.1778)
							(mid -0.137521 0.162921)
							(end -0.1524 0.127)
						)
						(arc
							(start -0.1524 -0.127)
							(mid -0.137521 -0.162921)
							(end -0.1016 -0.1778)
						)
						(arc
							(start 0.1016 -0.1778)
							(mid 0.137521 -0.162921)
							(end 0.1524 -0.127)
						)
					)
					(width 0)
					(fill yes)
				)
			)
		)
	)
	(footprint ""
		(layer "B.Cu")
		(at 94.398592 -85.095842)
		(property "Reference" "TP28"
			(at 0 0 0)
			(layer "B.SilkS")
			(hide yes)
			(effects
				(font
					(size 1.27 1.27)
				)
				(justify mirror)
			)
		)
		(property "Value" "TPAD28-2-GP"
			(at 0.0127 -1.6637 0)
			(unlocked yes)
			(layer "B.Fab")
			(hide yes)
			(effects
				(font
					(size 1.016 1.016)
					(thickness 0.1524)
				)
				(justify mirror)
			)
		)
		(property "Device Type" "TPAD28"
			(at 0.0127 -3.1877 0)
			(unlocked yes)
			(layer "B.Fab")
			(hide yes)
			(effects
				(font
					(size 1.016 1.016)
					(thickness 0.1524)
				)
				(justify mirror)
			)
		)
		(duplicate_pad_numbers_are_jumpers no)
		(fp_poly
			(pts
				(arc
					(start 0.3556 0)
					(mid -0.3556 0)
					(end 0.3556 0)
				)
			)
			(stroke
				(width 0)
				(type default)
			)
			(fill no)
			(layer "B.CrtYd")
		)
		(fp_poly
			(pts
				(arc
					(start 0.6096 0)
					(mid -0.6096 0)
					(end 0.6096 0)
				)
			)
			(stroke
				(width 0)
				(type default)
			)
			(fill no)
			(layer "B.Fab")
		)
		(pad "1" smd circle
			(at 0 0 180)
			(size 0.7112 0.7112)
			(layers "B.Cu" "B.Mask" "B.Paste")
			(net "ICE_RESET_N")
		)
	)
	(footprint ""
		(layer "B.Cu")
		(at 181.269386 -21.841968 90)
		(property "Reference" "C326"
			(at 0 0 90)
			(layer "B.SilkS")
			(hide yes)
			(effects
				(font
					(size 1.27 1.27)
				)
				(justify mirror)
			)
		)
		(property "Value" "SCD22U10V1KX-GP"
			(at 2.8321 -1.7399 90)
			(unlocked yes)
			(layer "B.Fab")
			(hide yes)
			(effects
				(font
					(size 1.016 1.016)
					(thickness 0.1524)
				)
				(justify mirror)
			)
		)
		(property "Device Type" "C0201H13"
			(at 2.8321 -3.2639 90)
			(unlocked yes)
			(layer "B.Fab")
			(hide yes)
			(effects
				(font
					(size 1.016 1.016)
					(thickness 0.1524)
				)
				(justify mirror)
			)
		)
		(duplicate_pad_numbers_are_jumpers no)
		(fp_rect
			(start 0.2794 0.6477)
			(end -0.2794 -0.6477)
			(stroke
				(width 0)
				(type default)
			)
			(fill no)
			(layer "B.CrtYd")
		)
		(fp_rect
			(start 0.2794 0.6477)
			(end -0.2794 -0.6477)
			(stroke
				(width 0)
				(type default)
			)
			(fill no)
			(layer "B.Fab")
		)
		(pad "1" smd custom
			(at 0 -0.2794 270)
			(size 0.0762 0.0762)
			(layers "B.Cu" "B.Mask" "B.Paste")
			(net "PCIE_SCC_TO_COMP_C_7_DN")
			(options
				(clearance outline)
				(anchor circle)
			)
			(primitives
				(gr_poly
					(pts
						(arc
							(start 0.1524 0.127)
							(mid 0.137521 0.162921)
							(end 0.1016 0.1778)
						)
						(arc
							(start -0.1016 0.1778)
							(mid -0.137521 0.162921)
							(end -0.1524 0.127)
						)
						(arc
							(start -0.1524 -0.127)
							(mid -0.137521 -0.162921)
							(end -0.1016 -0.1778)
						)
						(arc
							(start 0.1016 -0.1778)
							(mid 0.137521 -0.162921)
							(end 0.1524 -0.127)
						)
					)
					(width 0)
					(fill yes)
				)
			)
		)
		(pad "2" smd custom
			(at 0 0.2794 270)
			(size 0.0762 0.0762)
			(layers "B.Cu" "B.Mask" "B.Paste")
			(net "PCIE_SCC_TO_COMP_7_DN")
			(options
				(clearance outline)
				(anchor circle)
			)
			(primitives
				(gr_poly
					(pts
						(arc
							(start 0.1524 0.127)
							(mid 0.137521 0.162921)
							(end 0.1016 0.1778)
						)
						(arc
							(start -0.1016 0.1778)
							(mid -0.137521 0.162921)
							(end -0.1524 0.127)
						)
						(arc
							(start -0.1524 -0.127)
							(mid -0.137521 -0.162921)
							(end -0.1016 -0.1778)
						)
						(arc
							(start 0.1016 -0.1778)
							(mid 0.137521 -0.162921)
							(end 0.1524 -0.127)
						)
					)
					(width 0)
					(fill yes)
				)
			)
		)
	)
	(footprint ""
		(layer "B.Cu")
		(at 118.8466 -89.535 180)
		(property "Reference" "R565"
			(at 0 0 0)
			(layer "B.SilkS")
			(hide yes)
			(effects
				(font
					(size 1.27 1.27)
				)
				(justify mirror)
			)
		)
		(property "Value" "10KR2F-2-GP"
			(at -0.064008 -3.993896 180)
			(unlocked yes)
			(layer "B.Fab")
			(hide yes)
			(effects
				(font
					(size 1.016 1.016)
					(thickness 0.1524)
				)
				(justify mirror)
			)
		)
		(property "Device Type" "R402H16"
			(at -0.064008 -5.517896 180)
			(unlocked yes)
			(layer "B.Fab")
			(hide yes)
			(effects
				(font
					(size 1.016 1.016)
					(thickness 0.1524)
				)
				(justify mirror)
			)
		)
		(duplicate_pad_numbers_are_jumpers no)
		(fp_line
			(start 0.508 -0.9398)
			(end 0.508 0.9398)
			(stroke
				(width 0.1524)
				(type default)
			)
			(layer "B.SilkS")
		)
		(fp_line
			(start -0.508 -0.9398)
			(end 0.508 -0.9398)
			(stroke
				(width 0.1524)
				(type default)
			)
			(layer "B.SilkS")
		)
		(fp_rect
			(start 0.508 0.9398)
			(end -0.508 -0.9398)
			(stroke
				(width 0)
				(type default)
			)
			(fill no)
			(layer "B.CrtYd")
		)
		(fp_rect
			(start 0.508 0.9398)
			(end -0.508 -0.9398)
			(stroke
				(width 0)
				(type default)
			)
			(fill no)
			(layer "B.Fab")
		)
		(pad "1" smd custom
			(at 0 -0.4445)
			(size 0.1397 0.1397)
			(layers "B.Cu" "B.Mask" "B.Paste")
			(net "COMP_SPARE_0_LS")
			(options
				(clearance outline)
				(anchor circle)
			)
			(primitives
				(gr_poly
					(pts
						(arc
							(start -0.1778 0.2794)
							(mid -0.249642 0.249642)
							(end -0.2794 0.1778)
						)
						(arc
							(start -0.2794 -0.1778)
							(mid -0.249642 -0.249642)
							(end -0.1778 -0.2794)
						)
						(arc
							(start 0.1778 -0.2794)
							(mid 0.249642 -0.249642)
							(end 0.2794 -0.1778)
						)
						(arc
							(start 0.2794 0.1778)
							(mid 0.249642 0.249642)
							(end 0.1778 0.2794)
						)
					)
					(width 0)
					(fill yes)
				)
			)
		)
		(pad "2" smd custom
			(at 0 0.4445)
			(size 0.1397 0.1397)
			(layers "B.Cu" "B.Mask" "B.Paste")
			(net "P1V8_E")
			(options
				(clearance outline)
				(anchor circle)
			)
			(primitives
				(gr_poly
					(pts
						(arc
							(start -0.1778 0.2794)
							(mid -0.249642 0.249642)
							(end -0.2794 0.1778)
						)
						(arc
							(start -0.2794 -0.1778)
							(mid -0.249642 -0.249642)
							(end -0.1778 -0.2794)
						)
						(arc
							(start 0.1778 -0.2794)
							(mid 0.249642 -0.249642)
							(end 0.2794 -0.1778)
						)
						(arc
							(start 0.2794 0.1778)
							(mid 0.249642 0.249642)
							(end 0.1778 0.2794)
						)
					)
					(width 0)
					(fill yes)
				)
			)
		)
	)
	(footprint ""
		(layer "B.Cu")
		(at 187.12942 -42.296588 90)
		(property "Reference" "TP91"
			(at 0 0 90)
			(layer "B.SilkS")
			(hide yes)
			(effects
				(font
					(size 1.27 1.27)
				)
				(justify mirror)
			)
		)
		(property "Value" "TPAD28-2-GP"
			(at 0.0127 -1.6637 90)
			(unlocked yes)
			(layer "B.Fab")
			(hide yes)
			(effects
				(font
					(size 1.016 1.016)
					(thickness 0.1524)
				)
				(justify mirror)
			)
		)
		(property "Device Type" "TPAD28"
			(at 0.0127 -3.1877 90)
			(unlocked yes)
			(layer "B.Fab")
			(hide yes)
			(effects
				(font
					(size 1.016 1.016)
					(thickness 0.1524)
				)
				(justify mirror)
			)
		)
		(duplicate_pad_numbers_are_jumpers no)
		(fp_poly
			(pts
				(arc
					(start 0 0.3556)
					(mid 0 -0.3556)
					(end 0 0.3556)
				)
			)
			(stroke
				(width 0)
				(type default)
			)
			(fill no)
			(layer "B.CrtYd")
		)
		(fp_poly
			(pts
				(arc
					(start 0 0.6096)
					(mid 0 -0.6096)
					(end 0 0.6096)
				)
			)
			(stroke
				(width 0)
				(type default)
			)
			(fill no)
			(layer "B.Fab")
		)
		(pad "1" smd circle
			(at 0 0 270)
			(size 0.7112 0.7112)
			(layers "B.Cu" "B.Mask" "B.Paste")
			(net "IOC_GPIO_32")
		)
	)
	(footprint ""
		(layer "B.Cu")
		(at 116.459 -44.2214 180)
		(property "Reference" "C62"
			(at 0 0 0)
			(layer "B.SilkS")
			(hide yes)
			(effects
				(font
					(size 1.27 1.27)
				)
				(justify mirror)
			)
		)
		(property "Value" "SCD01U16V1KX-GP"
			(at 2.8321 -1.7399 180)
			(unlocked yes)
			(layer "B.Fab")
			(hide yes)
			(effects
				(font
					(size 1.016 1.016)
					(thickness 0.1524)
				)
				(justify mirror)
			)
		)
		(property "Device Type" "C0201H13"
			(at 2.8321 -3.2639 180)
			(unlocked yes)
			(layer "B.Fab")
			(hide yes)
			(effects
				(font
					(size 1.016 1.016)
					(thickness 0.1524)
				)
				(justify mirror)
			)
		)
		(duplicate_pad_numbers_are_jumpers no)
		(fp_rect
			(start 0.2794 0.6477)
			(end -0.2794 -0.6477)
			(stroke
				(width 0)
				(type default)
			)
			(fill no)
			(layer "B.CrtYd")
		)
		(fp_rect
			(start 0.2794 0.6477)
			(end -0.2794 -0.6477)
			(stroke
				(width 0)
				(type default)
			)
			(fill no)
			(layer "B.Fab")
		)
		(pad "1" smd custom
			(at 0 -0.2794)
			(size 0.0762 0.0762)
			(layers "B.Cu" "B.Mask" "B.Paste")
			(net "PHY_DPB_TO_SCC_33_DN")
			(options
				(clearance outline)
				(anchor circle)
			)
			(primitives
				(gr_poly
					(pts
						(arc
							(start 0.1524 0.127)
							(mid 0.137521 0.162921)
							(end 0.1016 0.1778)
						)
						(arc
							(start -0.1016 0.1778)
							(mid -0.137521 0.162921)
							(end -0.1524 0.127)
						)
						(arc
							(start -0.1524 -0.127)
							(mid -0.137521 -0.162921)
							(end -0.1016 -0.1778)
						)
						(arc
							(start 0.1016 -0.1778)
							(mid 0.137521 -0.162921)
							(end 0.1524 -0.127)
						)
					)
					(width 0)
					(fill yes)
				)
			)
		)
		(pad "2" smd custom
			(at 0 0.2794)
			(size 0.0762 0.0762)
			(layers "B.Cu" "B.Mask" "B.Paste")
			(net "PHY_DPB_TO_SCC_C_33_DN")
			(options
				(clearance outline)
				(anchor circle)
			)
			(primitives
				(gr_poly
					(pts
						(arc
							(start 0.1524 0.127)
							(mid 0.137521 0.162921)
							(end 0.1016 0.1778)
						)
						(arc
							(start -0.1016 0.1778)
							(mid -0.137521 0.162921)
							(end -0.1524 0.127)
						)
						(arc
							(start -0.1524 -0.127)
							(mid -0.137521 -0.162921)
							(end -0.1016 -0.1778)
						)
						(arc
							(start 0.1016 -0.1778)
							(mid 0.137521 -0.162921)
							(end 0.1524 -0.127)
						)
					)
					(width 0)
					(fill yes)
				)
			)
		)
	)
	(footprint ""
		(layer "B.Cu")
		(at 112.649 -68.6562)
		(property "Reference" "C177"
			(at 0 0 0)
			(layer "B.SilkS")
			(hide yes)
			(effects
				(font
					(size 1.27 1.27)
				)
				(justify mirror)
			)
		)
		(property "Value" "SCD1U6D3V1KX-GP"
			(at 2.8321 -1.7399 0)
			(unlocked yes)
			(layer "B.Fab")
			(hide yes)
			(effects
				(font
					(size 1.016 1.016)
					(thickness 0.1524)
				)
				(justify mirror)
			)
		)
		(property "Device Type" "C0201H13"
			(at 2.8321 -3.2639 0)
			(unlocked yes)
			(layer "B.Fab")
			(hide yes)
			(effects
				(font
					(size 1.016 1.016)
					(thickness 0.1524)
				)
				(justify mirror)
			)
		)
		(duplicate_pad_numbers_are_jumpers no)
		(fp_rect
			(start 0.2794 0.6477)
			(end -0.2794 -0.6477)
			(stroke
				(width 0)
				(type default)
			)
			(fill no)
			(layer "B.CrtYd")
		)
		(fp_rect
			(start 0.2794 0.6477)
			(end -0.2794 -0.6477)
			(stroke
				(width 0)
				(type default)
			)
			(fill no)
			(layer "B.Fab")
		)
		(pad "1" smd custom
			(at 0 -0.2794 180)
			(size 0.0762 0.0762)
			(layers "B.Cu" "B.Mask" "B.Paste")
			(net "P0V9")
			(options
				(clearance outline)
				(anchor circle)
			)
			(primitives
				(gr_poly
					(pts
						(arc
							(start 0.1524 0.127)
							(mid 0.137521 0.162921)
							(end 0.1016 0.1778)
						)
						(arc
							(start -0.1016 0.1778)
							(mid -0.137521 0.162921)
							(end -0.1524 0.127)
						)
						(arc
							(start -0.1524 -0.127)
							(mid -0.137521 -0.162921)
							(end -0.1016 -0.1778)
						)
						(arc
							(start 0.1016 -0.1778)
							(mid 0.137521 -0.162921)
							(end 0.1524 -0.127)
						)
					)
					(width 0)
					(fill yes)
				)
			)
		)
		(pad "2" smd custom
			(at 0 0.2794 180)
			(size 0.0762 0.0762)
			(layers "B.Cu" "B.Mask" "B.Paste")
			(net "GND")
			(options
				(clearance outline)
				(anchor circle)
			)
			(primitives
				(gr_poly
					(pts
						(arc
							(start 0.1524 0.127)
							(mid 0.137521 0.162921)
							(end 0.1016 0.1778)
						)
						(arc
							(start -0.1016 0.1778)
							(mid -0.137521 0.162921)
							(end -0.1524 0.127)
						)
						(arc
							(start -0.1524 -0.127)
							(mid -0.137521 -0.162921)
							(end -0.1016 -0.1778)
						)
						(arc
							(start 0.1016 -0.1778)
							(mid 0.137521 -0.162921)
							(end 0.1524 -0.127)
						)
					)
					(width 0)
					(fill yes)
				)
			)
		)
	)
	(footprint ""
		(layer "B.Cu")
		(at 186.563 -28.8036 90)
		(property "Reference" "TP73"
			(at 0 0 90)
			(layer "B.SilkS")
			(hide yes)
			(effects
				(font
					(size 1.27 1.27)
				)
				(justify mirror)
			)
		)
		(property "Value" "TPAD28-2-GP"
			(at 0.0127 -1.6637 90)
			(unlocked yes)
			(layer "B.Fab")
			(hide yes)
			(effects
				(font
					(size 1.016 1.016)
					(thickness 0.1524)
				)
				(justify mirror)
			)
		)
		(property "Device Type" "TPAD28"
			(at 0.0127 -3.1877 90)
			(unlocked yes)
			(layer "B.Fab")
			(hide yes)
			(effects
				(font
					(size 1.016 1.016)
					(thickness 0.1524)
				)
				(justify mirror)
			)
		)
		(duplicate_pad_numbers_are_jumpers no)
		(fp_poly
			(pts
				(arc
					(start 0 0.3556)
					(mid 0 -0.3556)
					(end 0 0.3556)
				)
			)
			(stroke
				(width 0)
				(type default)
			)
			(fill no)
			(layer "B.CrtYd")
		)
		(fp_poly
			(pts
				(arc
					(start 0 0.6096)
					(mid 0 -0.6096)
					(end 0 0.6096)
				)
			)
			(stroke
				(width 0)
				(type default)
			)
			(fill no)
			(layer "B.Fab")
		)
		(pad "1" smd circle
			(at 0 0 270)
			(size 0.7112 0.7112)
			(layers "B.Cu" "B.Mask" "B.Paste")
			(net "IOC_GPIO_20")
		)
	)
)
